# BASEBOARD_FAB2 (Tioga Pass) — schematic netlist excerpt (pin names and nets, part order shuffled) for the footprints in the layout excerpt that follows; sources: Cadence DE-HDL packaged netlist, KiCad conversion of Wiwynn_Tioga_Pass_MB.brd

R3R3  RES  33.2 1% CHIP  pkg 0402  page 92 : A = PWRGD_CPUPWRGD_R1 ; B = PWRGD_CPUPWRGD
R8D38  RES  100.0K 1% CHIP  pkg 0402  page 196 : A = P12V ; B = A_PG_P12V_MAIN
C1T3  CAP_A  0.1UF 16V 10% X7R  pkg 0402V  page 139 : A = P3V3_STBY ; B = GND

(kicad_pcb
	(version 20260206)
	(generator "pcbnew")
	(generator_version "10.0")
	(general
		(thickness 1.6)
		(legacy_teardrops no)
	)
	(paper "A4")
	(title_block
		(title "Wiwynn_Tioga_Pass_MB.brd")
		(comment 1 "Tioga Pass / footprints 2522-2524 of 4770")
	)
	(layers
		(0 "F.Cu" signal "TOP")
		(4 "In1.Cu" signal "L2GND")
		(6 "In2.Cu" signal "L3")
		(8 "In3.Cu" signal "L4GND")
		(10 "In4.Cu" signal "L5")
		(12 "In5.Cu" signal "L6GND")
		(14 "In6.Cu" signal "L7VCC")
		(16 "In7.Cu" signal "L8VCC")
		(18 "In8.Cu" signal "L9GND")
		(20 "In9.Cu" signal "L10")
		(22 "In10.Cu" signal "L11GND")
		(24 "In11.Cu" signal "L12")
		(26 "In12.Cu" signal "L13GND")
		(2 "B.Cu" signal "BOTTOM")
		(9 "F.Adhes" user "F.Adhesive")
		(11 "B.Adhes" user "B.Adhesive")
		(13 "F.Paste" user "Package Geometry/Pastemask Top")
		(15 "B.Paste" user "Package Geometry/Pastemask Bottom")
		(5 "F.SilkS" user "Ref Des/Silkscreen Top")
		(7 "B.SilkS" user "Ref Des/Silkscreen Bottom")
		(1 "F.Mask" user "Board Geometry/Soldermask Top")
		(3 "B.Mask" user "Board Geometry/Soldermask Bottom")
		(17 "Dwgs.User" user "User.Drawings")
		(19 "Cmts.User" user "User.Comments")
		(21 "Eco1.User" user "User.Eco1")
		(23 "Eco2.User" user "User.Eco2")
		(25 "Edge.Cuts" user "Board Geometry/Outline")
		(27 "Margin" user)
		(31 "F.CrtYd" user "Package Geometry/Place Bound Top")
		(29 "B.CrtYd" user "Package Geometry/Place Bound Bottom")
		(35 "F.Fab" user "Ref Des/Assembly Top")
		(33 "B.Fab" user "Ref Des/Assembly Bottom")
	)
	(footprint ""
		(layer "B.Cu")
		(at 486.7402 -39.7002 180)
		(property "Reference" "C1T3"
			(at 0 0 0)
			(layer "B.SilkS")
			(hide yes)
			(effects
				(font
					(size 1.27 1.27)
				)
				(justify mirror)
			)
		)
		(property "Value" ""
			(at 0 0 0)
			(layer "B.Fab")
			(effects
				(font
					(size 1.27 1.27)
				)
				(justify mirror)
			)
		)
		(duplicate_pad_numbers_are_jumpers no)
		(fp_poly
			(pts
				(xy -0.3048 -0.1016) (xy -0.3048 0.9906) (xy 0.3048 0.9906) (xy 0.3048 -0.1016)
			)
			(stroke
				(width 0)
				(type default)
			)
			(fill no)
			(layer "B.CrtYd")
		)
		(fp_line
			(start 0.3048 0.9906)
			(end -0.3048 0.9906)
			(stroke
				(width 0.1)
				(type default)
			)
			(layer "B.Fab")
		)
		(fp_line
			(start 0.3048 -0.1016)
			(end 0.3048 0.9906)
			(stroke
				(width 0.1)
				(type default)
			)
			(layer "B.Fab")
		)
		(fp_line
			(start -0.3048 0.9906)
			(end -0.3048 -0.1016)
			(stroke
				(width 0.1)
				(type default)
			)
			(layer "B.Fab")
		)
		(fp_line
			(start -0.3048 -0.1016)
			(end 0.3048 -0.1016)
			(stroke
				(width 0.1)
				(type default)
			)
			(layer "B.Fab")
		)
		(pad "1" smd rect
			(at 0 0)
			(size 0.508 0.508)
			(layers "B.Cu" "B.Mask" "B.Paste")
			(net "P3V3_STBY")
		)
		(pad "2" smd rect
			(at 0 0.889)
			(size 0.508 0.508)
			(layers "B.Cu" "B.Mask" "B.Paste")
			(net "GND")
		)
		(zone
			(layer "B.Cu")
			(hatch none 0.5)
			(connect_pads
				(clearance 0)
			)
			(min_thickness 0.25)
			(keepout
				(tracks not_allowed)
				(vias allowed)
				(pads allowed)
				(copperpour not_allowed)
				(footprints allowed)
			)
			(placement
				(enabled no)
				(sheetname "")
			)
			(fill
				(thermal_gap 0.5)
				(thermal_bridge_width 0.5)
				(island_removal_mode 0)
			)
			(polygon
				(pts
					(xy 486.4862 -40.3352) (xy 486.9942 -40.3352) (xy 486.9942 -39.9542) (xy 486.4862 -39.9542)
				)
			)
		)
		(zone
			(layer "B.Cu")
			(hatch none 0.5)
			(connect_pads
				(clearance 0)
			)
			(min_thickness 0.25)
			(keepout
				(tracks allowed)
				(vias not_allowed)
				(pads allowed)
				(copperpour not_allowed)
				(footprints allowed)
			)
			(placement
				(enabled no)
				(sheetname "")
			)
			(fill
				(thermal_gap 0.5)
				(thermal_bridge_width 0.5)
				(island_removal_mode 0)
			)
			(polygon
				(pts
					(xy 486.4862 -39.9542) (xy 486.9942 -39.9542) (xy 486.9942 -40.3352) (xy 486.4862 -40.3352)
				)
			)
		)
	)
	(footprint ""
		(layer "B.Cu")
		(at 408.051 -6.9215 180)
		(property "Reference" "R8D38"
			(at 0 0 0)
			(layer "B.SilkS")
			(hide yes)
			(effects
				(font
					(size 1.27 1.27)
				)
				(justify mirror)
			)
		)
		(property "Value" ""
			(at 0 0 0)
			(layer "B.Fab")
			(effects
				(font
					(size 1.27 1.27)
				)
				(justify mirror)
			)
		)
		(duplicate_pad_numbers_are_jumpers no)
		(fp_poly
			(pts
				(xy 0.2794 -0.1016) (xy -0.2794 -0.1016) (xy -0.2794 0.9906) (xy 0.2794 0.9906)
			)
			(stroke
				(width 0)
				(type default)
			)
			(fill no)
			(layer "B.CrtYd")
		)
		(fp_line
			(start 0.2794 0.9906)
			(end -0.2794 0.9906)
			(stroke
				(width 0.1)
				(type default)
			)
			(layer "B.Fab")
		)
		(fp_line
			(start 0.2794 -0.1016)
			(end 0.2794 0.9906)
			(stroke
				(width 0.1)
				(type default)
			)
			(layer "B.Fab")
		)
		(fp_line
			(start -0.2794 0.9906)
			(end -0.2794 -0.1016)
			(stroke
				(width 0.1)
				(type default)
			)
			(layer "B.Fab")
		)
		(fp_line
			(start -0.2794 -0.1016)
			(end 0.2794 -0.1016)
			(stroke
				(width 0.1)
				(type default)
			)
			(layer "B.Fab")
		)
		(pad "1" smd rect
			(at 0 0)
			(size 0.508 0.508)
			(layers "B.Cu" "B.Mask" "B.Paste")
			(net "P12V")
		)
		(pad "2" smd rect
			(at 0 0.889)
			(size 0.508 0.508)
			(layers "B.Cu" "B.Mask" "B.Paste")
			(net "A_PG_P12V_MAIN")
		)
		(zone
			(layer "B.Cu")
			(hatch none 0.5)
			(connect_pads
				(clearance 0)
			)
			(min_thickness 0.25)
			(keepout
				(tracks not_allowed)
				(vias allowed)
				(pads allowed)
				(copperpour not_allowed)
				(footprints allowed)
			)
			(placement
				(enabled no)
				(sheetname "")
			)
			(fill
				(thermal_gap 0.5)
				(thermal_bridge_width 0.5)
				(island_removal_mode 0)
			)
			(polygon
				(pts
					(xy 407.797 -7.5565) (xy 408.305 -7.5565) (xy 408.305 -7.1755) (xy 407.797 -7.1755)
				)
			)
		)
		(zone
			(layer "B.Cu")
			(hatch none 0.5)
			(connect_pads
				(clearance 0)
			)
			(min_thickness 0.25)
			(keepout
				(tracks allowed)
				(vias not_allowed)
				(pads allowed)
				(copperpour not_allowed)
				(footprints allowed)
			)
			(placement
				(enabled no)
				(sheetname "")
			)
			(fill
				(thermal_gap 0.5)
				(thermal_bridge_width 0.5)
				(island_removal_mode 0)
			)
			(polygon
				(pts
					(xy 407.797 -7.1755) (xy 408.305 -7.1755) (xy 408.305 -7.5565) (xy 407.797 -7.5565)
				)
			)
		)
	)
	(footprint ""
		(layer "B.Cu")
		(at 365.76 -62.2935 180)
		(property "Reference" "R3R3"
			(at 0 0 0)
			(layer "B.SilkS")
			(hide yes)
			(effects
				(font
					(size 1.27 1.27)
				)
				(justify mirror)
			)
		)
		(property "Value" ""
			(at 0 0 0)
			(layer "B.Fab")
			(effects
				(font
					(size 1.27 1.27)
				)
				(justify mirror)
			)
		)
		(duplicate_pad_numbers_are_jumpers no)
		(fp_poly
			(pts
				(xy 0.2794 -0.1016) (xy -0.2794 -0.1016) (xy -0.2794 0.9906) (xy 0.2794 0.9906)
			)
			(stroke
				(width 0)
				(type default)
			)
			(fill no)
			(layer "B.CrtYd")
		)
		(fp_line
			(start 0.2794 0.9906)
			(end -0.2794 0.9906)
			(stroke
				(width 0.1)
				(type default)
			)
			(layer "B.Fab")
		)
		(fp_line
			(start 0.2794 -0.1016)
			(end 0.2794 0.9906)
			(stroke
				(width 0.1)
				(type default)
			)
			(layer "B.Fab")
		)
		(fp_line
			(start -0.2794 0.9906)
			(end -0.2794 -0.1016)
			(stroke
				(width 0.1)
				(type default)
			)
			(layer "B.Fab")
		)
		(fp_line
			(start -0.2794 -0.1016)
			(end 0.2794 -0.1016)
			(stroke
				(width 0.1)
				(type default)
			)
			(layer "B.Fab")
		)
		(pad "1" smd rect
			(at 0 0)
			(size 0.508 0.508)
			(layers "B.Cu" "B.Mask" "B.Paste")
			(net "PWRGD_CPUPWRGD_R1")
		)
		(pad "2" smd rect
			(at 0 0.889)
			(size 0.508 0.508)
			(layers "B.Cu" "B.Mask" "B.Paste")
			(net "PWRGD_CPUPWRGD")
		)
		(zone
			(layer "B.Cu")
			(hatch none 0.5)
			(connect_pads
				(clearance 0)
			)
			(min_thickness 0.25)
			(keepout
				(tracks not_allowed)
				(vias allowed)
				(pads allowed)
				(copperpour not_allowed)
				(footprints allowed)
			)
			(placement
				(enabled no)
				(sheetname "")
			)
			(fill
				(thermal_gap 0.5)
				(thermal_bridge_width 0.5)
				(island_removal_mode 0)
			)
			(polygon
				(pts
					(xy 365.506 -62.9285) (xy 366.014 -62.9285) (xy 366.014 -62.5475) (xy 365.506 -62.5475)
				)
			)
		)
		(zone
			(layer "B.Cu")
			(hatch none 0.5)
			(connect_pads
				(clearance 0)
			)
			(min_thickness 0.25)
			(keepout
				(tracks allowed)
				(vias not_allowed)
				(pads allowed)
				(copperpour not_allowed)
				(footprints allowed)
			)
			(placement
				(enabled no)
				(sheetname "")
			)
			(fill
				(thermal_gap 0.5)
				(thermal_bridge_width 0.5)
				(island_removal_mode 0)
			)
			(polygon
				(pts
					(xy 365.506 -62.5475) (xy 366.014 -62.5475) (xy 366.014 -62.9285) (xy 365.506 -62.9285)
				)
			)
		)
	)
)
